(kicad_pcb
	(version 20260206)
	(generator "pcbnew")
	(generator_version "10.0")
	(general
		(thickness 1.6)
		(legacy_teardrops no)
	)
	(paper "A4")
	(title_block
		(title "04192023_DAF0TMB3IC0_F0TG_MB_C_brd_V02_OCP.brd")
		(comment 1 "Grand Teton / footprints 3342-3348 of 8354")
	)
	(layers
		(0 "F.Cu" signal "TOP")
		(4 "In1.Cu" signal "GND")
		(6 "In2.Cu" signal "IN1")
		(8 "In3.Cu" signal "GND1")
		(10 "In4.Cu" signal "IN2")
		(12 "In5.Cu" signal "GND2")
		(14 "In6.Cu" signal "IN3")
		(16 "In7.Cu" signal "GND3")
		(18 "In8.Cu" signal "VCC")
		(20 "In9.Cu" signal "VCC1")
		(22 "In10.Cu" signal "GND4")
		(24 "In11.Cu" signal "IN4")
		(26 "In12.Cu" signal "GND5")
		(28 "In13.Cu" signal "IN5")
		(30 "In14.Cu" signal "GND6")
		(32 "In15.Cu" signal "IN6")
		(34 "In16.Cu" signal "GND7")
		(2 "B.Cu" signal "BOTTOM")
		(9 "F.Adhes" user "F.Adhesive")
		(11 "B.Adhes" user "B.Adhesive")
		(13 "F.Paste" user "Package Geometry/Pastemask Top")
		(15 "B.Paste" user "Package Geometry/Pastemask Bottom")
		(5 "F.SilkS" user "Ref Des/Silkscreen Top")
		(7 "B.SilkS" user "Ref Des/Silkscreen Bottom")
		(1 "F.Mask" user "Board Geometry/Soldermask Top")
		(3 "B.Mask" user "Board Geometry/Soldermask Bottom")
		(17 "Dwgs.User" user "User.Drawings")
		(19 "Cmts.User" user "User.Comments")
		(21 "Eco1.User" user "User.Eco1")
		(23 "Eco2.User" user "User.Eco2")
		(25 "Edge.Cuts" user "Board Geometry/Outline")
		(27 "Margin" user)
		(31 "F.CrtYd" user "Package Geometry/Place Bound Top")
		(29 "B.CrtYd" user "Package Geometry/Place Bound Bottom")
		(35 "F.Fab" user "Ref Des/Assembly Top")
		(33 "B.Fab" user "Ref Des/Assembly Bottom")
	)
	(footprint ""
		(layer "F.Cu")
		(at 156.30779 -98.755708 90)
		(property "Reference" "C1877"
			(at 0 0 90)
			(layer "F.SilkS")
			(hide yes)
			(effects
				(font
					(size 1.27 1.27)
				)
			)
		)
		(property "Value" ""
			(at 0 0 90)
			(layer "F.Fab")
			(effects
				(font
					(size 1.27 1.27)
				)
			)
		)
		(duplicate_pad_numbers_are_jumpers no)
		(fp_line
			(start 0.7874 -0.4064)
			(end 0.7874 0.4064)
			(stroke
				(width 0.1524)
				(type default)
			)
			(layer "F.SilkS")
		)
		(fp_line
			(start -0.7874 -0.4064)
			(end 0.7874 -0.4064)
			(stroke
				(width 0.1524)
				(type default)
			)
			(layer "F.SilkS")
		)
		(fp_line
			(start 0.7874 0.4064)
			(end -0.7874 0.4064)
			(stroke
				(width 0.1524)
				(type default)
			)
			(layer "F.SilkS")
		)
		(fp_line
			(start -0.7874 0.4064)
			(end -0.7874 -0.4064)
			(stroke
				(width 0.1524)
				(type default)
			)
			(layer "F.SilkS")
		)
		(fp_line
			(start -0.12065 -0.305054)
			(end -0.12065 -0.2794)
			(stroke
				(width 0.1)
				(type default)
			)
			(layer "F.Fab")
		)
		(fp_line
			(start -0.67945 -0.305054)
			(end -0.12065 -0.305054)
			(stroke
				(width 0.1)
				(type default)
			)
			(layer "F.Fab")
		)
		(fp_line
			(start 0.67945 -0.3048)
			(end 0.67945 0.3048)
			(stroke
				(width 0.1)
				(type default)
			)
			(layer "F.Fab")
		)
		(fp_line
			(start 0.12065 -0.3048)
			(end 0.67945 -0.3048)
			(stroke
				(width 0.1)
				(type default)
			)
			(layer "F.Fab")
		)
		(fp_line
			(start 0.12065 -0.2794)
			(end 0.12065 -0.3048)
			(stroke
				(width 0.1)
				(type default)
			)
			(layer "F.Fab")
		)
		(fp_line
			(start -0.12065 -0.2794)
			(end 0.12065 -0.2794)
			(stroke
				(width 0.1)
				(type default)
			)
			(layer "F.Fab")
		)
		(fp_line
			(start 0.120396 0.2794)
			(end -0.12065 0.2794)
			(stroke
				(width 0.1)
				(type default)
			)
			(layer "F.Fab")
		)
		(fp_line
			(start -0.12065 0.2794)
			(end -0.12065 0.3048)
			(stroke
				(width 0.1)
				(type default)
			)
			(layer "F.Fab")
		)
		(fp_line
			(start 0.67945 0.3048)
			(end 0.120396 0.3048)
			(stroke
				(width 0.1)
				(type default)
			)
			(layer "F.Fab")
		)
		(fp_line
			(start 0.120396 0.3048)
			(end 0.120396 0.2794)
			(stroke
				(width 0.1)
				(type default)
			)
			(layer "F.Fab")
		)
		(fp_line
			(start -0.12065 0.3048)
			(end -0.67945 0.3048)
			(stroke
				(width 0.1)
				(type default)
			)
			(layer "F.Fab")
		)
		(fp_line
			(start -0.67945 0.3048)
			(end -0.67945 -0.305054)
			(stroke
				(width 0.1)
				(type default)
			)
			(layer "F.Fab")
		)
		(pad "1" smd circle
			(at -0.40005 0 90)
			(size 0 0)
			(layers "F.Cu" "F.Mask" "F.Paste")
			(net "P3V3_AUX")
		)
		(pad "2" smd circle
			(at 0.40005 0 90)
			(size 0 0)
			(layers "F.Cu" "F.Mask" "F.Paste")
			(net "GND")
		)
	)
	(footprint ""
		(layer "F.Cu")
		(at 133.728714 -151.319484)
		(property "Reference" "PR214"
			(at 0 0 0)
			(layer "F.SilkS")
			(hide yes)
			(effects
				(font
					(size 1.27 1.27)
				)
			)
		)
		(property "Value" ""
			(at 0 0 0)
			(layer "F.Fab")
			(effects
				(font
					(size 1.27 1.27)
				)
			)
		)
		(duplicate_pad_numbers_are_jumpers no)
		(fp_line
			(start -0.7874 -0.4064)
			(end 0.7874 -0.4064)
			(stroke
				(width 0.1524)
				(type default)
			)
			(layer "F.SilkS")
		)
		(fp_line
			(start -0.7874 0.4064)
			(end -0.7874 -0.4064)
			(stroke
				(width 0.1524)
				(type default)
			)
			(layer "F.SilkS")
		)
		(fp_line
			(start 0.7874 -0.4064)
			(end 0.7874 0.4064)
			(stroke
				(width 0.1524)
				(type default)
			)
			(layer "F.SilkS")
		)
		(fp_line
			(start 0.7874 0.4064)
			(end -0.7874 0.4064)
			(stroke
				(width 0.1524)
				(type default)
			)
			(layer "F.SilkS")
		)
		(fp_line
			(start -0.67945 -0.305054)
			(end -0.12065 -0.305054)
			(stroke
				(width 0.1)
				(type default)
			)
			(layer "F.Fab")
		)
		(fp_line
			(start -0.67945 0.3048)
			(end -0.67945 -0.305054)
			(stroke
				(width 0.1)
				(type default)
			)
			(layer "F.Fab")
		)
		(fp_line
			(start -0.12065 -0.305054)
			(end -0.12065 -0.2794)
			(stroke
				(width 0.1)
				(type default)
			)
			(layer "F.Fab")
		)
		(fp_line
			(start -0.12065 -0.2794)
			(end 0.12065 -0.2794)
			(stroke
				(width 0.1)
				(type default)
			)
			(layer "F.Fab")
		)
		(fp_line
			(start -0.12065 0.2794)
			(end -0.12065 0.3048)
			(stroke
				(width 0.1)
				(type default)
			)
			(layer "F.Fab")
		)
		(fp_line
			(start -0.12065 0.3048)
			(end -0.67945 0.3048)
			(stroke
				(width 0.1)
				(type default)
			)
			(layer "F.Fab")
		)
		(fp_line
			(start 0.120396 0.2794)
			(end -0.12065 0.2794)
			(stroke
				(width 0.1)
				(type default)
			)
			(layer "F.Fab")
		)
		(fp_line
			(start 0.120396 0.3048)
			(end 0.120396 0.2794)
			(stroke
				(width 0.1)
				(type default)
			)
			(layer "F.Fab")
		)
		(fp_line
			(start 0.12065 -0.3048)
			(end 0.67945 -0.3048)
			(stroke
				(width 0.1)
				(type default)
			)
			(layer "F.Fab")
		)
		(fp_line
			(start 0.12065 -0.2794)
			(end 0.12065 -0.3048)
			(stroke
				(width 0.1)
				(type default)
			)
			(layer "F.Fab")
		)
		(fp_line
			(start 0.67945 -0.3048)
			(end 0.67945 0.3048)
			(stroke
				(width 0.1)
				(type default)
			)
			(layer "F.Fab")
		)
		(fp_line
			(start 0.67945 0.3048)
			(end 0.120396 0.3048)
			(stroke
				(width 0.1)
				(type default)
			)
			(layer "F.Fab")
		)
		(pad "1" smd circle
			(at -0.40005 0)
			(size 0 0)
			(layers "F.Cu" "F.Mask" "F.Paste")
			(net "GND")
		)
		(pad "2" smd circle
			(at 0.40005 0)
			(size 0 0)
			(layers "F.Cu" "F.Mask" "F.Paste")
			(net "PVDDCR_SOC_P1_LSET3")
		)
	)
	(footprint ""
		(layer "F.Cu")
		(at 339.713062 -333.290164 90)
		(property "Reference" "PR158"
			(at 0 0 90)
			(layer "F.SilkS")
			(hide yes)
			(effects
				(font
					(size 1.27 1.27)
				)
			)
		)
		(property "Value" ""
			(at 0 0 90)
			(layer "F.Fab")
			(effects
				(font
					(size 1.27 1.27)
				)
			)
		)
		(duplicate_pad_numbers_are_jumpers no)
		(fp_line
			(start 0.7874 -0.4064)
			(end 0.7874 0.4064)
			(stroke
				(width 0.1524)
				(type default)
			)
			(layer "F.SilkS")
		)
		(fp_line
			(start -0.7874 -0.4064)
			(end 0.7874 -0.4064)
			(stroke
				(width 0.1524)
				(type default)
			)
			(layer "F.SilkS")
		)
		(fp_line
			(start 0.7874 0.4064)
			(end -0.7874 0.4064)
			(stroke
				(width 0.1524)
				(type default)
			)
			(layer "F.SilkS")
		)
		(fp_line
			(start -0.7874 0.4064)
			(end -0.7874 -0.4064)
			(stroke
				(width 0.1524)
				(type default)
			)
			(layer "F.SilkS")
		)
		(fp_line
			(start -0.12065 -0.305054)
			(end -0.12065 -0.2794)
			(stroke
				(width 0.1)
				(type default)
			)
			(layer "F.Fab")
		)
		(fp_line
			(start -0.67945 -0.305054)
			(end -0.12065 -0.305054)
			(stroke
				(width 0.1)
				(type default)
			)
			(layer "F.Fab")
		)
		(fp_line
			(start 0.67945 -0.3048)
			(end 0.67945 0.3048)
			(stroke
				(width 0.1)
				(type default)
			)
			(layer "F.Fab")
		)
		(fp_line
			(start 0.12065 -0.3048)
			(end 0.67945 -0.3048)
			(stroke
				(width 0.1)
				(type default)
			)
			(layer "F.Fab")
		)
		(fp_line
			(start 0.12065 -0.2794)
			(end 0.12065 -0.3048)
			(stroke
				(width 0.1)
				(type default)
			)
			(layer "F.Fab")
		)
		(fp_line
			(start -0.12065 -0.2794)
			(end 0.12065 -0.2794)
			(stroke
				(width 0.1)
				(type default)
			)
			(layer "F.Fab")
		)
		(fp_line
			(start 0.120396 0.2794)
			(end -0.12065 0.2794)
			(stroke
				(width 0.1)
				(type default)
			)
			(layer "F.Fab")
		)
		(fp_line
			(start -0.12065 0.2794)
			(end -0.12065 0.3048)
			(stroke
				(width 0.1)
				(type default)
			)
			(layer "F.Fab")
		)
		(fp_line
			(start 0.67945 0.3048)
			(end 0.120396 0.3048)
			(stroke
				(width 0.1)
				(type default)
			)
			(layer "F.Fab")
		)
		(fp_line
			(start 0.120396 0.3048)
			(end 0.120396 0.2794)
			(stroke
				(width 0.1)
				(type default)
			)
			(layer "F.Fab")
		)
		(fp_line
			(start -0.12065 0.3048)
			(end -0.67945 0.3048)
			(stroke
				(width 0.1)
				(type default)
			)
			(layer "F.Fab")
		)
		(fp_line
			(start -0.67945 0.3048)
			(end -0.67945 -0.305054)
			(stroke
				(width 0.1)
				(type default)
			)
			(layer "F.Fab")
		)
		(pad "1" smd circle
			(at -0.40005 0 90)
			(size 0 0)
			(layers "F.Cu" "F.Mask" "F.Paste")
			(net "SW_PVDDCR_CPU1_P0_SW5_RC")
		)
		(pad "2" smd circle
			(at 0.40005 0 90)
			(size 0 0)
			(layers "F.Cu" "F.Mask" "F.Paste")
			(net "GND")
		)
	)
	(footprint ""
		(layer "F.Cu")
		(at 409.565348 -17.624298 90)
		(property "Reference" "C1794"
			(at 0 0 90)
			(layer "F.SilkS")
			(hide yes)
			(effects
				(font
					(size 1.27 1.27)
				)
			)
		)
		(property "Value" ""
			(at 0 0 90)
			(layer "F.Fab")
			(effects
				(font
					(size 1.27 1.27)
				)
			)
		)
		(duplicate_pad_numbers_are_jumpers no)
		(fp_line
			(start 0.299974 -0.150114)
			(end 0.299974 0.150114)
			(stroke
				(width 0.1)
				(type default)
			)
			(layer "F.Fab")
		)
		(fp_line
			(start -0.299974 -0.150114)
			(end 0.299974 -0.150114)
			(stroke
				(width 0.1)
				(type default)
			)
			(layer "F.Fab")
		)
		(fp_line
			(start 0.299974 0.150114)
			(end -0.299974 0.150114)
			(stroke
				(width 0.1)
				(type default)
			)
			(layer "F.Fab")
		)
		(fp_line
			(start -0.299974 0.150114)
			(end -0.299974 -0.150114)
			(stroke
				(width 0.1)
				(type default)
			)
			(layer "F.Fab")
		)
		(pad "1" smd rect
			(at -0.2667 0 90)
			(size 0.3048 0.381)
			(layers "F.Cu" "F.Mask" "F.Paste")
			(net "P5E_CPU0_G3_TX_C_DN<8>")
		)
		(pad "2" smd rect
			(at 0.2667 0 90)
			(size 0.3048 0.381)
			(layers "F.Cu" "F.Mask" "F.Paste")
			(net "P5E_CPU0_G3_TX_DN<8>")
		)
	)
	(footprint ""
		(layer "F.Cu")
		(at 355.157278 -163.26231)
		(property "Reference" "PC570_5"
			(at 0 0 0)
			(layer "F.SilkS")
			(hide yes)
			(effects
				(font
					(size 1.27 1.27)
				)
			)
		)
		(property "Value" ""
			(at 0 0 0)
			(layer "F.Fab")
			(effects
				(font
					(size 1.27 1.27)
				)
			)
		)
		(duplicate_pad_numbers_are_jumpers no)
		(fp_line
			(start -0.7874 -0.4064)
			(end 0.7874 -0.4064)
			(stroke
				(width 0.1524)
				(type default)
			)
			(layer "F.SilkS")
		)
		(fp_line
			(start -0.7874 0.4064)
			(end -0.7874 -0.4064)
			(stroke
				(width 0.1524)
				(type default)
			)
			(layer "F.SilkS")
		)
		(fp_line
			(start 0.7874 -0.4064)
			(end 0.7874 0.4064)
			(stroke
				(width 0.1524)
				(type default)
			)
			(layer "F.SilkS")
		)
		(fp_line
			(start 0.7874 0.4064)
			(end -0.7874 0.4064)
			(stroke
				(width 0.1524)
				(type default)
			)
			(layer "F.SilkS")
		)
		(fp_line
			(start -0.67945 -0.305054)
			(end -0.12065 -0.305054)
			(stroke
				(width 0.1)
				(type default)
			)
			(layer "F.Fab")
		)
		(fp_line
			(start -0.67945 0.3048)
			(end -0.67945 -0.305054)
			(stroke
				(width 0.1)
				(type default)
			)
			(layer "F.Fab")
		)
		(fp_line
			(start -0.12065 -0.305054)
			(end -0.12065 -0.2794)
			(stroke
				(width 0.1)
				(type default)
			)
			(layer "F.Fab")
		)
		(fp_line
			(start -0.12065 -0.2794)
			(end 0.12065 -0.2794)
			(stroke
				(width 0.1)
				(type default)
			)
			(layer "F.Fab")
		)
		(fp_line
			(start -0.12065 0.2794)
			(end -0.12065 0.3048)
			(stroke
				(width 0.1)
				(type default)
			)
			(layer "F.Fab")
		)
		(fp_line
			(start -0.12065 0.3048)
			(end -0.67945 0.3048)
			(stroke
				(width 0.1)
				(type default)
			)
			(layer "F.Fab")
		)
		(fp_line
			(start 0.120396 0.2794)
			(end -0.12065 0.2794)
			(stroke
				(width 0.1)
				(type default)
			)
			(layer "F.Fab")
		)
		(fp_line
			(start 0.120396 0.3048)
			(end 0.120396 0.2794)
			(stroke
				(width 0.1)
				(type default)
			)
			(layer "F.Fab")
		)
		(fp_line
			(start 0.12065 -0.3048)
			(end 0.67945 -0.3048)
			(stroke
				(width 0.1)
				(type default)
			)
			(layer "F.Fab")
		)
		(fp_line
			(start 0.12065 -0.2794)
			(end 0.12065 -0.3048)
			(stroke
				(width 0.1)
				(type default)
			)
			(layer "F.Fab")
		)
		(fp_line
			(start 0.67945 -0.3048)
			(end 0.67945 0.3048)
			(stroke
				(width 0.1)
				(type default)
			)
			(layer "F.Fab")
		)
		(fp_line
			(start 0.67945 0.3048)
			(end 0.120396 0.3048)
			(stroke
				(width 0.1)
				(type default)
			)
			(layer "F.Fab")
		)
		(pad "1" smd circle
			(at -0.40005 0)
			(size 0 0)
			(layers "F.Cu" "F.Mask" "F.Paste")
			(net "SW_P12V_AUX_PVDDCR_CPU0_P0_FLT")
		)
		(pad "2" smd circle
			(at 0.40005 0)
			(size 0 0)
			(layers "F.Cu" "F.Mask" "F.Paste")
			(net "GND")
		)
	)
	(footprint ""
		(layer "F.Cu")
		(at 450.060314 -25.10028 -90)
		(property "Reference" "PR3792"
			(at 0 0 270)
			(layer "F.SilkS")
			(hide yes)
			(effects
				(font
					(size 1.27 1.27)
				)
			)
		)
		(property "Value" ""
			(at 0 0 270)
			(layer "F.Fab")
			(effects
				(font
					(size 1.27 1.27)
				)
			)
		)
		(duplicate_pad_numbers_are_jumpers no)
		(fp_line
			(start -0.7874 0.4064)
			(end -0.7874 -0.4064)
			(stroke
				(width 0.1524)
				(type default)
			)
			(layer "F.SilkS")
		)
		(fp_line
			(start 0.7874 0.4064)
			(end -0.7874 0.4064)
			(stroke
				(width 0.1524)
				(type default)
			)
			(layer "F.SilkS")
		)
		(fp_line
			(start -0.7874 -0.4064)
			(end 0.7874 -0.4064)
			(stroke
				(width 0.1524)
				(type default)
			)
			(layer "F.SilkS")
		)
		(fp_line
			(start 0.7874 -0.4064)
			(end 0.7874 0.4064)
			(stroke
				(width 0.1524)
				(type default)
			)
			(layer "F.SilkS")
		)
		(fp_line
			(start -0.67945 0.3048)
			(end -0.67945 -0.305054)
			(stroke
				(width 0.1)
				(type default)
			)
			(layer "F.Fab")
		)
		(fp_line
			(start -0.12065 0.3048)
			(end -0.67945 0.3048)
			(stroke
				(width 0.1)
				(type default)
			)
			(layer "F.Fab")
		)
		(fp_line
			(start 0.120396 0.3048)
			(end 0.120396 0.2794)
			(stroke
				(width 0.1)
				(type default)
			)
			(layer "F.Fab")
		)
		(fp_line
			(start 0.67945 0.3048)
			(end 0.120396 0.3048)
			(stroke
				(width 0.1)
				(type default)
			)
			(layer "F.Fab")
		)
		(fp_line
			(start -0.12065 0.2794)
			(end -0.12065 0.3048)
			(stroke
				(width 0.1)
				(type default)
			)
			(layer "F.Fab")
		)
		(fp_line
			(start 0.120396 0.2794)
			(end -0.12065 0.2794)
			(stroke
				(width 0.1)
				(type default)
			)
			(layer "F.Fab")
		)
		(fp_line
			(start -0.12065 -0.2794)
			(end 0.12065 -0.2794)
			(stroke
				(width 0.1)
				(type default)
			)
			(layer "F.Fab")
		)
		(fp_line
			(start 0.12065 -0.2794)
			(end 0.12065 -0.3048)
			(stroke
				(width 0.1)
				(type default)
			)
			(layer "F.Fab")
		)
		(fp_line
			(start 0.12065 -0.3048)
			(end 0.67945 -0.3048)
			(stroke
				(width 0.1)
				(type default)
			)
			(layer "F.Fab")
		)
		(fp_line
			(start 0.67945 -0.3048)
			(end 0.67945 0.3048)
			(stroke
				(width 0.1)
				(type default)
			)
			(layer "F.Fab")
		)
		(fp_line
			(start -0.67945 -0.305054)
			(end -0.12065 -0.305054)
			(stroke
				(width 0.1)
				(type default)
			)
			(layer "F.Fab")
		)
		(fp_line
			(start -0.12065 -0.305054)
			(end -0.12065 -0.2794)
			(stroke
				(width 0.1)
				(type default)
			)
			(layer "F.Fab")
		)
		(pad "1" smd circle
			(at -0.40005 0 270)
			(size 0 0)
			(layers "F.Cu" "F.Mask" "F.Paste")
			(net "P12V_AUX")
		)
		(pad "2" smd circle
			(at 0.40005 0 270)
			(size 0 0)
			(layers "F.Cu" "F.Mask" "F.Paste")
			(net "P12V_OCP_VCC_1")
		)
	)
	(footprint ""
		(layer "F.Cu")
		(at 193.089022 -25.965912 90)
		(property "Reference" "R4013"
			(at 0 0 90)
			(layer "F.SilkS")
			(hide yes)
			(effects
				(font
					(size 1.27 1.27)
				)
			)
		)
		(property "Value" ""
			(at 0 0 90)
			(layer "F.Fab")
			(effects
				(font
					(size 1.27 1.27)
				)
			)
		)
		(duplicate_pad_numbers_are_jumpers no)
		(fp_line
			(start 0.7874 -0.4064)
			(end 0.7874 0.4064)
			(stroke
				(width 0.1524)
				(type default)
			)
			(layer "F.SilkS")
		)
		(fp_line
			(start -0.7874 -0.4064)
			(end 0.7874 -0.4064)
			(stroke
				(width 0.1524)
				(type default)
			)
			(layer "F.SilkS")
		)
		(fp_line
			(start 0.7874 0.4064)
			(end -0.7874 0.4064)
			(stroke
				(width 0.1524)
				(type default)
			)
			(layer "F.SilkS")
		)
		(fp_line
			(start -0.7874 0.4064)
			(end -0.7874 -0.4064)
			(stroke
				(width 0.1524)
				(type default)
			)
			(layer "F.SilkS")
		)
		(fp_line
			(start -0.12065 -0.305054)
			(end -0.12065 -0.2794)
			(stroke
				(width 0.1)
				(type default)
			)
			(layer "F.Fab")
		)
		(fp_line
			(start -0.67945 -0.305054)
			(end -0.12065 -0.305054)
			(stroke
				(width 0.1)
				(type default)
			)
			(layer "F.Fab")
		)
		(fp_line
			(start 0.67945 -0.3048)
			(end 0.67945 0.3048)
			(stroke
				(width 0.1)
				(type default)
			)
			(layer "F.Fab")
		)
		(fp_line
			(start 0.12065 -0.3048)
			(end 0.67945 -0.3048)
			(stroke
				(width 0.1)
				(type default)
			)
			(layer "F.Fab")
		)
		(fp_line
			(start 0.12065 -0.2794)
			(end 0.12065 -0.3048)
			(stroke
				(width 0.1)
				(type default)
			)
			(layer "F.Fab")
		)
		(fp_line
			(start -0.12065 -0.2794)
			(end 0.12065 -0.2794)
			(stroke
				(width 0.1)
				(type default)
			)
			(layer "F.Fab")
		)
		(fp_line
			(start 0.120396 0.2794)
			(end -0.12065 0.2794)
			(stroke
				(width 0.1)
				(type default)
			)
			(layer "F.Fab")
		)
		(fp_line
			(start -0.12065 0.2794)
			(end -0.12065 0.3048)
			(stroke
				(width 0.1)
				(type default)
			)
			(layer "F.Fab")
		)
		(fp_line
			(start 0.67945 0.3048)
			(end 0.120396 0.3048)
			(stroke
				(width 0.1)
				(type default)
			)
			(layer "F.Fab")
		)
		(fp_line
			(start 0.120396 0.3048)
			(end 0.120396 0.2794)
			(stroke
				(width 0.1)
				(type default)
			)
			(layer "F.Fab")
		)
		(fp_line
			(start -0.12065 0.3048)
			(end -0.67945 0.3048)
			(stroke
				(width 0.1)
				(type default)
			)
			(layer "F.Fab")
		)
		(fp_line
			(start -0.67945 0.3048)
			(end -0.67945 -0.305054)
			(stroke
				(width 0.1)
				(type default)
			)
			(layer "F.Fab")
		)
		(pad "1" smd circle
			(at -0.40005 0 90)
			(size 0 0)
			(layers "F.Cu" "F.Mask" "F.Paste")
			(net "P3V3_AUX")
		)
		(pad "2" smd circle
			(at 0.40005 0 90)
			(size 0 0)
			(layers "F.Cu" "F.Mask" "F.Paste")
			(net "P12V_SCM_FAULT_R_N")
		)
	)
)
